(kicad_pcb
	(version 20260206)
	(generator "pcbnew")
	(generator_version "10.0")
	(general
		(thickness 1.6)
		(legacy_teardrops no)
	)
	(paper "A4")
	(title_block
		(title "04192023_DAF0TMB3IC0_F0TG_MB_C_brd_V02_OCP.brd")
		(comment 1 "Grand Teton / footprint 2783 of 8354 (U26), pads 1539-1649 of 6102")
	)
	(layers
		(0 "F.Cu" signal "TOP")
		(4 "In1.Cu" signal "GND")
		(6 "In2.Cu" signal "IN1")
		(8 "In3.Cu" signal "GND1")
		(10 "In4.Cu" signal "IN2")
		(12 "In5.Cu" signal "GND2")
		(14 "In6.Cu" signal "IN3")
		(16 "In7.Cu" signal "GND3")
		(18 "In8.Cu" signal "VCC")
		(20 "In9.Cu" signal "VCC1")
		(22 "In10.Cu" signal "GND4")
		(24 "In11.Cu" signal "IN4")
		(26 "In12.Cu" signal "GND5")
		(28 "In13.Cu" signal "IN5")
		(30 "In14.Cu" signal "GND6")
		(32 "In15.Cu" signal "IN6")
		(34 "In16.Cu" signal "GND7")
		(2 "B.Cu" signal "BOTTOM")
		(9 "F.Adhes" user "F.Adhesive")
		(11 "B.Adhes" user "B.Adhesive")
		(13 "F.Paste" user "Package Geometry/Pastemask Top")
		(15 "B.Paste" user "Package Geometry/Pastemask Bottom")
		(5 "F.SilkS" user "Ref Des/Silkscreen Top")
		(7 "B.SilkS" user "Ref Des/Silkscreen Bottom")
		(1 "F.Mask" user "Board Geometry/Soldermask Top")
		(3 "B.Mask" user "Board Geometry/Soldermask Bottom")
		(17 "Dwgs.User" user "User.Drawings")
		(19 "Cmts.User" user "User.Comments")
		(21 "Eco1.User" user "User.Eco1")
		(23 "Eco2.User" user "User.Eco2")
		(25 "Edge.Cuts" user "Board Geometry/Outline")
		(27 "Margin" user)
		(31 "F.CrtYd" user "Package Geometry/Place Bound Top")
		(29 "B.CrtYd" user "Package Geometry/Place Bound Bottom")
		(35 "F.Fab" user "Ref Des/Assembly Top")
		(33 "B.Fab" user "Ref Des/Assembly Bottom")
	)
	(footprint ""
		(layer "F.Cu")
		(at 111.927894 -258.880356 180)
		(property "Reference" "U26"
			(at -45.05579 -61.794136 0)
			(unlocked yes)
			(layer "F.SilkS")
			(effects
				(font
					(size 0.7874 0.5842)
					(thickness 0.1524)
				)
			)
		)
		(property "Value" ""
			(at 0 0 180)
			(layer "F.Fab")
			(effects
				(font
					(size 1.27 1.27)
				)
			)
		)
		(duplicate_pad_numbers_are_jumpers no)
		(pad "BA1" smd circle
			(at -34.159952 -4.409948 180)
			(size 0.450088 0.450088)
			(layers "F.Cu" "F.Mask" "F.Paste")
			(net "GND")
		)
		(pad "BA2" smd circle
			(at -33.219898 -4.409948 180)
			(size 0.450088 0.450088)
			(layers "F.Cu" "F.Mask" "F.Paste")
			(net "M_G_CPU1_SA_CA<4>")
		)
		(pad "BA3" smd circle
			(at -32.280098 -4.409948 180)
			(size 0.450088 0.450088)
			(layers "F.Cu" "F.Mask" "F.Paste")
			(net "M_G_CPU1_SA_CA<3>")
		)
		(pad "BA4" smd circle
			(at -31.340044 -4.409948 180)
			(size 0.450088 0.450088)
			(layers "F.Cu" "F.Mask" "F.Paste")
			(net "PVDDCR_SOC_P1")
		)
		(pad "BA5" smd circle
			(at -30.39999 -4.409948 180)
			(size 0.450088 0.450088)
			(layers "F.Cu" "F.Mask" "F.Paste")
			(net "M_K_CPU1_SA_CA<4>")
		)
		(pad "BA6" smd circle
			(at -29.459936 -4.409948 180)
			(size 0.450088 0.450088)
			(layers "F.Cu" "F.Mask" "F.Paste")
			(net "GND")
		)
		(pad "BA7" smd circle
			(at -28.519882 -4.409948 180)
			(size 0.450088 0.450088)
			(layers "F.Cu" "F.Mask" "F.Paste")
			(net "M_K_CPU1_SA_CA<3>")
		)
		(pad "BA8" smd circle
			(at -27.580082 -4.409948 180)
			(size 0.450088 0.450088)
			(layers "F.Cu" "F.Mask" "F.Paste")
			(net "GND")
		)
		(pad "BA9" smd circle
			(at -26.640028 -4.409948 180)
			(size 0.450088 0.450088)
			(layers "F.Cu" "F.Mask" "F.Paste")
			(net "M_L_CPU1_SA_CA<4>")
		)
		(pad "BA10" smd circle
			(at -25.699974 -4.409948 180)
			(size 0.450088 0.450088)
			(layers "F.Cu" "F.Mask" "F.Paste")
			(net "M_L_CPU1_SA_CA<3>")
		)
		(pad "BA11" smd circle
			(at -24.75992 -4.409948 180)
			(size 0.450088 0.450088)
			(layers "F.Cu" "F.Mask" "F.Paste")
			(net "PVDDCR_SOC_P1")
		)
		(pad "BA12" smd circle
			(at -23.82012 -4.409948 180)
			(size 0.450088 0.450088)
			(layers "F.Cu" "F.Mask" "F.Paste")
			(net "M_H_CPU1_SA_CA<4>")
		)
		(pad "BA13" smd circle
			(at -22.880066 -4.409948 180)
			(size 0.450088 0.450088)
			(layers "F.Cu" "F.Mask" "F.Paste")
			(net "GND")
		)
		(pad "BA14" smd circle
			(at -21.940012 -4.409948 180)
			(size 0.450088 0.450088)
			(layers "F.Cu" "F.Mask" "F.Paste")
			(net "M_H_CPU1_SA_CA<3>")
		)
		(pad "BA15" smd circle
			(at -20.999958 -4.409948 180)
			(size 0.450088 0.450088)
			(layers "F.Cu" "F.Mask" "F.Paste")
			(net "GND")
		)
		(pad "BA16" smd circle
			(at -20.059904 -4.409948 180)
			(size 0.450088 0.450088)
			(layers "F.Cu" "F.Mask" "F.Paste")
			(net "M_J_CPU1_SA_CA<4>")
		)
		(pad "BA17" smd circle
			(at -19.120104 -4.409948 180)
			(size 0.450088 0.450088)
			(layers "F.Cu" "F.Mask" "F.Paste")
			(net "M_J_CPU1_SA_CA<3>")
		)
		(pad "BA18" smd circle
			(at -18.18005 -4.409948 180)
			(size 0.450088 0.450088)
			(layers "F.Cu" "F.Mask" "F.Paste")
			(net "PVDDCR_SOC_P1")
		)
		(pad "BA19" smd circle
			(at -17.239996 -4.409948 180)
			(size 0.450088 0.450088)
			(layers "F.Cu" "F.Mask" "F.Paste")
			(net "M_I_CPU1_SA_CA<4>")
		)
		(pad "BA20" smd circle
			(at -16.299942 -4.409948 180)
			(size 0.450088 0.450088)
			(layers "F.Cu" "F.Mask" "F.Paste")
			(net "GND")
		)
		(pad "BA21" smd circle
			(at -15.359888 -4.409948 180)
			(size 0.450088 0.450088)
			(layers "F.Cu" "F.Mask" "F.Paste")
			(net "M_I_CPU1_SA_CA<3>")
		)
		(pad "BA22" smd circle
			(at -14.420088 -4.409948 180)
			(size 0.450088 0.450088)
			(layers "F.Cu" "F.Mask" "F.Paste")
			(net "GND")
		)
		(pad "BA23" smd circle
			(at -13.480034 -4.409948 180)
			(size 0.450088 0.450088)
			(layers "F.Cu" "F.Mask" "F.Paste")
			(net "PVDDCR_SOC_P1")
		)
		(pad "BA24" smd circle
			(at -12.53998 -4.409948 180)
			(size 0.450088 0.450088)
			(layers "F.Cu" "F.Mask" "F.Paste")
			(net "GND")
		)
		(pad "BA25" smd circle
			(at -11.599926 -4.409948 180)
			(size 0.450088 0.450088)
			(layers "F.Cu" "F.Mask" "F.Paste")
			(net "PVDDCR_SOC_P1")
		)
		(pad "BA26" smd circle
			(at -10.659872 -4.409948 180)
			(size 0.450088 0.450088)
			(layers "F.Cu" "F.Mask" "F.Paste")
			(net "GND")
		)
		(pad "BA27" smd circle
			(at -9.720072 -4.409948 180)
			(size 0.450088 0.450088)
			(layers "F.Cu" "F.Mask" "F.Paste")
			(net "PVDDCR_SOC_P1")
		)
		(pad "BA28" smd circle
			(at -8.780018 -4.409948 180)
			(size 0.450088 0.450088)
			(layers "F.Cu" "F.Mask" "F.Paste")
			(net "GND")
		)
		(pad "BA48" smd circle
			(at 9.079992 -4.409948 180)
			(size 0.450088 0.450088)
			(layers "F.Cu" "F.Mask" "F.Paste")
			(net "PVDDCR_SOC_P1")
		)
		(pad "BA49" smd circle
			(at 10.020046 -4.409948 180)
			(size 0.450088 0.450088)
			(layers "F.Cu" "F.Mask" "F.Paste")
			(net "GND")
		)
		(pad "BA50" smd circle
			(at 10.9601 -4.409948 180)
			(size 0.450088 0.450088)
			(layers "F.Cu" "F.Mask" "F.Paste")
			(net "PVDD18_S5_P1")
		)
		(pad "BA51" smd circle
			(at 11.8999 -4.409948 180)
			(size 0.450088 0.450088)
			(layers "F.Cu" "F.Mask" "F.Paste")
			(net "GND")
		)
		(pad "BA52" smd circle
			(at 12.839954 -4.409948 180)
			(size 0.450088 0.450088)
			(layers "F.Cu" "F.Mask" "F.Paste")
			(net "PVDD18_S5_P1")
		)
		(pad "BA53" smd circle
			(at 13.780008 -4.409948 180)
			(size 0.450088 0.450088)
			(layers "F.Cu" "F.Mask" "F.Paste")
			(net "GND")
		)
		(pad "BA54" smd circle
			(at 14.720062 -4.409948 180)
			(size 0.450088 0.450088)
			(layers "F.Cu" "F.Mask" "F.Paste")
			(net "PVDD18_S5_P1")
		)
		(pad "BA55" smd circle
			(at 15.660116 -4.409948 180)
			(size 0.450088 0.450088)
			(layers "F.Cu" "F.Mask" "F.Paste")
			(net "M_C_CPU1_SA_CA<3>")
		)
		(pad "BA56" smd circle
			(at 16.599916 -4.409948 180)
			(size 0.450088 0.450088)
			(layers "F.Cu" "F.Mask" "F.Paste")
			(net "GND")
		)
		(pad "BA57" smd circle
			(at 17.53997 -4.409948 180)
			(size 0.450088 0.450088)
			(layers "F.Cu" "F.Mask" "F.Paste")
			(net "M_C_CPU1_SA_CA<4>")
		)
		(pad "BA58" smd circle
			(at 18.480024 -4.409948 180)
			(size 0.450088 0.450088)
			(layers "F.Cu" "F.Mask" "F.Paste")
			(net "PVDDIO_P1")
		)
		(pad "BA59" smd circle
			(at 19.420078 -4.409948 180)
			(size 0.450088 0.450088)
			(layers "F.Cu" "F.Mask" "F.Paste")
			(net "M_D_CPU1_SA_CA<3>")
		)
		(pad "BA60" smd circle
			(at 20.359878 -4.409948 180)
			(size 0.450088 0.450088)
			(layers "F.Cu" "F.Mask" "F.Paste")
			(net "M_D_CPU1_SA_CA<4>")
		)
		(pad "BA61" smd circle
			(at 21.299932 -4.409948 180)
			(size 0.450088 0.450088)
			(layers "F.Cu" "F.Mask" "F.Paste")
			(net "GND")
		)
		(pad "BA62" smd circle
			(at 22.239986 -4.409948 180)
			(size 0.450088 0.450088)
			(layers "F.Cu" "F.Mask" "F.Paste")
			(net "M_B_CPU1_SA_CA<3>")
		)
		(pad "BA63" smd circle
			(at 23.18004 -4.409948 180)
			(size 0.450088 0.450088)
			(layers "F.Cu" "F.Mask" "F.Paste")
			(net "GND")
		)
		(pad "BA64" smd circle
			(at 24.120094 -4.409948 180)
			(size 0.450088 0.450088)
			(layers "F.Cu" "F.Mask" "F.Paste")
			(net "M_B_CPU1_SA_CA<4>")
		)
		(pad "BA65" smd circle
			(at 25.059894 -4.409948 180)
			(size 0.450088 0.450088)
			(layers "F.Cu" "F.Mask" "F.Paste")
			(net "PVDDIO_P1")
		)
		(pad "BA66" smd circle
			(at 25.999948 -4.409948 180)
			(size 0.450088 0.450088)
			(layers "F.Cu" "F.Mask" "F.Paste")
			(net "M_F_CPU1_SA_CA<3>")
		)
		(pad "BA67" smd circle
			(at 26.940002 -4.409948 180)
			(size 0.450088 0.450088)
			(layers "F.Cu" "F.Mask" "F.Paste")
			(net "M_F_CPU1_SA_CA<4>")
		)
		(pad "BA68" smd circle
			(at 27.880056 -4.409948 180)
			(size 0.450088 0.450088)
			(layers "F.Cu" "F.Mask" "F.Paste")
			(net "GND")
		)
		(pad "BA69" smd circle
			(at 28.82011 -4.409948 180)
			(size 0.450088 0.450088)
			(layers "F.Cu" "F.Mask" "F.Paste")
			(net "M_E_CPU1_SA_CA<3>")
		)
		(pad "BA70" smd circle
			(at 29.75991 -4.409948 180)
			(size 0.450088 0.450088)
			(layers "F.Cu" "F.Mask" "F.Paste")
			(net "GND")
		)
		(pad "BA71" smd circle
			(at 30.699964 -4.409948 180)
			(size 0.450088 0.450088)
			(layers "F.Cu" "F.Mask" "F.Paste")
			(net "M_E_CPU1_SA_CA<4>")
		)
		(pad "BA72" smd circle
			(at 31.640018 -4.409948 180)
			(size 0.450088 0.450088)
			(layers "F.Cu" "F.Mask" "F.Paste")
			(net "PVDDIO_P1")
		)
		(pad "BA73" smd circle
			(at 32.580072 -4.409948 180)
			(size 0.450088 0.450088)
			(layers "F.Cu" "F.Mask" "F.Paste")
			(net "M_A_CPU1_SA_CA<3>")
		)
		(pad "BA74" smd circle
			(at 33.519872 -4.409948 180)
			(size 0.450088 0.450088)
			(layers "F.Cu" "F.Mask" "F.Paste")
			(net "M_A_CPU1_SA_CA<4>")
		)
		(pad "BA75" smd circle
			(at 34.459926 -4.409948 180)
			(size 0.450088 0.450088)
			(layers "F.Cu" "F.Mask" "F.Paste")
			(net "GND")
		)
		(pad "BB2" smd circle
			(at -33.690052 -3.599942 180)
			(size 0.450088 0.450088)
			(layers "F.Cu" "F.Mask" "F.Paste")
			(net "M_G_CPU1_SA_CA<5>")
		)
		(pad "BB3" smd circle
			(at -32.749998 -3.599942 180)
			(size 0.450088 0.450088)
			(layers "F.Cu" "F.Mask" "F.Paste")
			(net "GND")
		)
		(pad "BB4" smd circle
			(at -31.809944 -3.599942 180)
			(size 0.450088 0.450088)
			(layers "F.Cu" "F.Mask" "F.Paste")
			(net "M_G_CPU1_SA_CA<6>")
		)
		(pad "BB5" smd circle
			(at -30.86989 -3.599942 180)
			(size 0.450088 0.450088)
			(layers "F.Cu" "F.Mask" "F.Paste")
			(net "GND")
		)
		(pad "BB6" smd circle
			(at -29.93009 -3.599942 180)
			(size 0.450088 0.450088)
			(layers "F.Cu" "F.Mask" "F.Paste")
			(net "M_K_CPU1_SA_CA<5>")
		)
		(pad "BB7" smd circle
			(at -28.990036 -3.599942 180)
			(size 0.450088 0.450088)
			(layers "F.Cu" "F.Mask" "F.Paste")
			(net "M_K_CPU1_SA_CA<6>")
		)
		(pad "BB8" smd circle
			(at -28.049982 -3.599942 180)
			(size 0.450088 0.450088)
			(layers "F.Cu" "F.Mask" "F.Paste")
			(net "GND")
		)
		(pad "BB9" smd circle
			(at -27.109928 -3.599942 180)
			(size 0.450088 0.450088)
			(layers "F.Cu" "F.Mask" "F.Paste")
			(net "M_L_CPU1_SA_CA<5>")
		)
		(pad "BB10" smd circle
			(at -26.170128 -3.599942 180)
			(size 0.450088 0.450088)
			(layers "F.Cu" "F.Mask" "F.Paste")
			(net "GND")
		)
		(pad "BB11" smd circle
			(at -25.230074 -3.599942 180)
			(size 0.450088 0.450088)
			(layers "F.Cu" "F.Mask" "F.Paste")
			(net "M_L_CPU1_SA_CA<6>")
		)
		(pad "BB12" smd circle
			(at -24.29002 -3.599942 180)
			(size 0.450088 0.450088)
			(layers "F.Cu" "F.Mask" "F.Paste")
			(net "GND")
		)
		(pad "BB13" smd circle
			(at -23.349966 -3.599942 180)
			(size 0.450088 0.450088)
			(layers "F.Cu" "F.Mask" "F.Paste")
			(net "M_H_CPU1_SA_CA<5>")
		)
		(pad "BB14" smd circle
			(at -22.409912 -3.599942 180)
			(size 0.450088 0.450088)
			(layers "F.Cu" "F.Mask" "F.Paste")
			(net "M_H_CPU1_SA_CA<6>")
		)
		(pad "BB15" smd circle
			(at -21.470112 -3.599942 180)
			(size 0.450088 0.450088)
			(layers "F.Cu" "F.Mask" "F.Paste")
			(net "GND")
		)
		(pad "BB16" smd circle
			(at -20.530058 -3.599942 180)
			(size 0.450088 0.450088)
			(layers "F.Cu" "F.Mask" "F.Paste")
			(net "M_J_CPU1_SA_CA<5>")
		)
		(pad "BB17" smd circle
			(at -19.590004 -3.599942 180)
			(size 0.450088 0.450088)
			(layers "F.Cu" "F.Mask" "F.Paste")
			(net "GND")
		)
		(pad "BB18" smd circle
			(at -18.64995 -3.599942 180)
			(size 0.450088 0.450088)
			(layers "F.Cu" "F.Mask" "F.Paste")
			(net "M_J_CPU1_SA_CA<6>")
		)
		(pad "BB19" smd circle
			(at -17.709896 -3.599942 180)
			(size 0.450088 0.450088)
			(layers "F.Cu" "F.Mask" "F.Paste")
			(net "GND")
		)
		(pad "BB20" smd circle
			(at -16.770096 -3.599942 180)
			(size 0.450088 0.450088)
			(layers "F.Cu" "F.Mask" "F.Paste")
			(net "M_I_CPU1_SA_CA<5>")
		)
		(pad "BB21" smd circle
			(at -15.830042 -3.599942 180)
			(size 0.450088 0.450088)
			(layers "F.Cu" "F.Mask" "F.Paste")
			(net "M_I_CPU1_SA_CA<6>")
		)
		(pad "BB22" smd circle
			(at -14.889988 -3.599942 180)
			(size 0.450088 0.450088)
			(layers "F.Cu" "F.Mask" "F.Paste")
			(net "PVDDCR_SOC_P1")
		)
		(pad "BB23" smd circle
			(at -13.949934 -3.599942 180)
			(size 0.450088 0.450088)
			(layers "F.Cu" "F.Mask" "F.Paste")
			(net "GND")
		)
		(pad "BB24" smd circle
			(at -13.00988 -3.599942 180)
			(size 0.450088 0.450088)
			(layers "F.Cu" "F.Mask" "F.Paste")
			(net "PVDDCR_SOC_P1")
		)
		(pad "BB25" smd circle
			(at -12.07008 -3.599942 180)
			(size 0.450088 0.450088)
			(layers "F.Cu" "F.Mask" "F.Paste")
			(net "GND")
		)
		(pad "BB26" smd circle
			(at -11.130026 -3.599942 180)
			(size 0.450088 0.450088)
			(layers "F.Cu" "F.Mask" "F.Paste")
			(net "PVDDCR_SOC_P1")
		)
		(pad "BB27" smd circle
			(at -10.189972 -3.599942 180)
			(size 0.450088 0.450088)
			(layers "F.Cu" "F.Mask" "F.Paste")
			(net "GND")
		)
		(pad "BB28" smd circle
			(at -9.249918 -3.599942 180)
			(size 0.450088 0.450088)
			(layers "F.Cu" "F.Mask" "F.Paste")
			(net "PVDDCR_SOC_P1")
		)
		(pad "BB48" smd circle
			(at 9.549892 -3.599942 180)
			(size 0.450088 0.450088)
			(layers "F.Cu" "F.Mask" "F.Paste")
			(net "GND")
		)
		(pad "BB49" smd circle
			(at 10.489946 -3.599942 180)
			(size 0.450088 0.450088)
			(layers "F.Cu" "F.Mask" "F.Paste")
			(net "PVDDCR_SOC_P1")
		)
		(pad "BB50" smd circle
			(at 11.43 -3.599942 180)
			(size 0.450088 0.450088)
			(layers "F.Cu" "F.Mask" "F.Paste")
			(net "GND")
		)
		(pad "BB51" smd circle
			(at 12.370054 -3.599942 180)
			(size 0.450088 0.450088)
			(layers "F.Cu" "F.Mask" "F.Paste")
			(net "PVDD18_S5_P1")
		)
		(pad "BB52" smd circle
			(at 13.310108 -3.599942 180)
			(size 0.450088 0.450088)
			(layers "F.Cu" "F.Mask" "F.Paste")
			(net "GND")
		)
		(pad "BB53" smd circle
			(at 14.249908 -3.599942 180)
			(size 0.450088 0.450088)
			(layers "F.Cu" "F.Mask" "F.Paste")
			(net "PVDD18_S5_P1")
		)
		(pad "BB54" smd circle
			(at 15.189962 -3.599942 180)
			(size 0.450088 0.450088)
			(layers "F.Cu" "F.Mask" "F.Paste")
			(net "GND")
		)
		(pad "BB55" smd circle
			(at 16.130016 -3.599942 180)
			(size 0.450088 0.450088)
			(layers "F.Cu" "F.Mask" "F.Paste")
			(net "M_C_CPU1_SA_CA<6>")
		)
		(pad "BB56" smd circle
			(at 17.07007 -3.599942 180)
			(size 0.450088 0.450088)
			(layers "F.Cu" "F.Mask" "F.Paste")
			(net "M_C_CPU1_SA_CA<5>")
		)
		(pad "BB57" smd circle
			(at 18.010124 -3.599942 180)
			(size 0.450088 0.450088)
			(layers "F.Cu" "F.Mask" "F.Paste")
			(net "GND")
		)
		(pad "BB58" smd circle
			(at 18.949924 -3.599942 180)
			(size 0.450088 0.450088)
			(layers "F.Cu" "F.Mask" "F.Paste")
			(net "M_D_CPU1_SA_CA<6>")
		)
		(pad "BB59" smd circle
			(at 19.889978 -3.599942 180)
			(size 0.450088 0.450088)
			(layers "F.Cu" "F.Mask" "F.Paste")
			(net "GND")
		)
		(pad "BB60" smd circle
			(at 20.830032 -3.599942 180)
			(size 0.450088 0.450088)
			(layers "F.Cu" "F.Mask" "F.Paste")
			(net "M_D_CPU1_SA_CA<5>")
		)
		(pad "BB61" smd circle
			(at 21.770086 -3.599942 180)
			(size 0.450088 0.450088)
			(layers "F.Cu" "F.Mask" "F.Paste")
			(net "GND")
		)
		(pad "BB62" smd circle
			(at 22.709886 -3.599942 180)
			(size 0.450088 0.450088)
			(layers "F.Cu" "F.Mask" "F.Paste")
			(net "M_B_CPU1_SA_CA<6>")
		)
		(pad "BB63" smd circle
			(at 23.64994 -3.599942 180)
			(size 0.450088 0.450088)
			(layers "F.Cu" "F.Mask" "F.Paste")
			(net "M_B_CPU1_SA_CA<5>")
		)
		(pad "BB64" smd circle
			(at 24.589994 -3.599942 180)
			(size 0.450088 0.450088)
			(layers "F.Cu" "F.Mask" "F.Paste")
			(net "GND")
		)
		(pad "BB65" smd circle
			(at 25.530048 -3.599942 180)
			(size 0.450088 0.450088)
			(layers "F.Cu" "F.Mask" "F.Paste")
			(net "M_F_CPU1_SA_CA<6>")
		)
		(pad "BB66" smd circle
			(at 26.470102 -3.599942 180)
			(size 0.450088 0.450088)
			(layers "F.Cu" "F.Mask" "F.Paste")
			(net "GND")
		)
		(pad "BB67" smd circle
			(at 27.409902 -3.599942 180)
			(size 0.450088 0.450088)
			(layers "F.Cu" "F.Mask" "F.Paste")
			(net "M_F_CPU1_SA_CA<5>")
		)
		(pad "BB68" smd circle
			(at 28.349956 -3.599942 180)
			(size 0.450088 0.450088)
			(layers "F.Cu" "F.Mask" "F.Paste")
			(net "GND")
		)
		(pad "BB69" smd circle
			(at 29.29001 -3.599942 180)
			(size 0.450088 0.450088)
			(layers "F.Cu" "F.Mask" "F.Paste")
			(net "M_E_CPU1_SA_CA<6>")
		)
		(pad "BB70" smd circle
			(at 30.230064 -3.599942 180)
			(size 0.450088 0.450088)
			(layers "F.Cu" "F.Mask" "F.Paste")
			(net "M_E_CPU1_SA_CA<5>")
		)
		(pad "BB71" smd circle
			(at 31.170118 -3.599942 180)
			(size 0.450088 0.450088)
			(layers "F.Cu" "F.Mask" "F.Paste")
			(net "GND")
		)
		(pad "BB72" smd circle
			(at 32.109918 -3.599942 180)
			(size 0.450088 0.450088)
			(layers "F.Cu" "F.Mask" "F.Paste")
			(net "M_A_CPU1_SA_CA<6>")
		)
		(pad "BB73" smd circle
			(at 33.049972 -3.599942 180)
			(size 0.450088 0.450088)
			(layers "F.Cu" "F.Mask" "F.Paste")
			(net "GND")
		)
		(pad "BB74" smd circle
			(at 33.990026 -3.599942 180)
			(size 0.450088 0.450088)
			(layers "F.Cu" "F.Mask" "F.Paste")
			(net "M_A_CPU1_SA_CA<5>")
		)
		(pad "BC1" smd circle
			(at -34.159952 -2.789936 180)
			(size 0.450088 0.450088)
			(layers "F.Cu" "F.Mask" "F.Paste")
			(net "GND")
		)
	)
)
